# TIMECARD (Time Appliance Project (Time Card)) — schematic netlist excerpt (pin names and nets, part order shuffled) for the footprints in the layout excerpt that follows; sources: Cadence DE-HDL packaged netlist, KiCad conversion of R4006-B0001-02_R01.brd

C89  CAPACITOR  0.1UF 25V 10%  pkg SMC_0402R_H022  page 24 : \1\ = XP3R3V_FPGA ; \2\ = SG
SP57  NULL  pkg DUMMY  page 34
SP26  SOLDER_PREFORM  pkg 0201_SOLDER_PREFORM_4MIL  page 34 : \1\ = NC ; \2\ = NC
L12  FERRITEBEAD  120OHM 25%  pkg SMC_0603R_H030  page 14 : \1\ = XP1R0V_FPGA_VCCINT ; \2\ = XP1R0V_FPGA

(kicad_pcb
	(version 20260206)
	(generator "pcbnew")
	(generator_version "10.0")
	(general
		(thickness 1.6)
		(legacy_teardrops no)
	)
	(paper "A4")
	(title_block
		(title "timecard-production-celestica-r4006 — R4006-B0001-02_R01.brd")
		(comment 1 "Time Appliance Project (Time Card) / footprints 357-360 of 1113")
	)
	(layers
		(0 "F.Cu" signal "TOP")
		(4 "In1.Cu" signal "L02_GND1")
		(6 "In2.Cu" signal "L03_SIG1")
		(8 "In3.Cu" signal "L04_GND2")
		(10 "In4.Cu" signal "L05_VCC1")
		(12 "In5.Cu" signal "L06_VCC2")
		(14 "In6.Cu" signal "L07_GND3")
		(16 "In7.Cu" signal "L08_SIG2")
		(18 "In8.Cu" signal "L09_GND4")
		(2 "B.Cu" signal "BOTTOM")
		(9 "F.Adhes" user "F.Adhesive")
		(11 "B.Adhes" user "B.Adhesive")
		(13 "F.Paste" user "Package Geometry/Pastemask Top")
		(15 "B.Paste" user "Package Geometry/Pastemask Bottom")
		(5 "F.SilkS" user "Ref Des/Silkscreen Top")
		(7 "B.SilkS" user "Ref Des/Silkscreen Bottom")
		(1 "F.Mask" user "Board Geometry/Soldermask Top")
		(3 "B.Mask" user "Board Geometry/Soldermask Bottom")
		(17 "Dwgs.User" user "User.Drawings")
		(19 "Cmts.User" user "User.Comments")
		(21 "Eco1.User" user "User.Eco1")
		(23 "Eco2.User" user "User.Eco2")
		(25 "Edge.Cuts" user "Board Geometry/Outline")
		(27 "Margin" user)
		(31 "F.CrtYd" user "Package Geometry/Place Bound Top")
		(29 "B.CrtYd" user "Package Geometry/Place Bound Bottom")
		(35 "F.Fab" user "Ref Des/Assembly Top")
		(33 "B.Fab" user "Ref Des/Assembly Bottom")
	)
	(footprint ""
		(layer "F.Cu")
		(at 111.887 -96.266)
		(property "Reference" "C89"
			(at 2.794 0.16637 0)
			(unlocked yes)
			(layer "F.SilkS")
			(effects
				(font
					(size 0.7874 0.5842)
					(thickness 0.1524)
				)
			)
		)
		(property "Value" "VAL*"
			(at 0.0762 2.067306 0)
			(unlocked yes)
			(layer "F.Fab")
			(hide yes)
			(effects
				(font
					(size 0.7874 0.5842)
					(thickness 0.1524)
				)
			)
		)
		(property "Tolerance" "TOL*"
			(at 0.0762 3.032506 0)
			(unlocked yes)
			(layer "Cmts.User")
			(hide yes)
			(effects
				(font
					(size 0.7874 0.5842)
					(thickness 0.1524)
				)
			)
		)
		(property "User Part Number" "PARTNUM*"
			(at 0.1016 4.023106 0)
			(unlocked yes)
			(layer "Cmts.User")
			(hide yes)
			(effects
				(font
					(size 0.7874 0.5842)
					(thickness 0.1524)
				)
			)
		)
		(property "Device Type" "CAPACITOR-G105-0B104-EK,0.1UF,A"
			(at 0.0508 1.127506 0)
			(unlocked yes)
			(layer "F.Fab")
			(hide yes)
			(effects
				(font
					(size 0.7874 0.5842)
					(thickness 0.1524)
				)
			)
		)
		(duplicate_pad_numbers_are_jumpers no)
		(fp_line
			(start -1.143 -0.5588)
			(end -1.143 0.5588)
			(stroke
				(width 0.1)
				(type default)
			)
			(layer "F.SilkS")
		)
		(fp_line
			(start -1.143 0.5588)
			(end 1.143 0.5588)
			(stroke
				(width 0.1)
				(type default)
			)
			(layer "F.SilkS")
		)
		(fp_line
			(start 1.143 -0.5588)
			(end -1.143 -0.5588)
			(stroke
				(width 0.1)
				(type default)
			)
			(layer "F.SilkS")
		)
		(fp_line
			(start 1.143 0.5588)
			(end 1.143 -0.5588)
			(stroke
				(width 0.1)
				(type default)
			)
			(layer "F.SilkS")
		)
		(fp_rect
			(start 1.143 -0.5588)
			(end -1.143 0.5588)
			(stroke
				(width 0)
				(type default)
			)
			(fill no)
			(layer "F.CrtYd")
		)
		(fp_line
			(start -0.508 -0.3048)
			(end -0.508 0.3048)
			(stroke
				(width 0.1)
				(type default)
			)
			(layer "F.Fab")
		)
		(fp_line
			(start -0.508 0.3048)
			(end 0.508 0.3048)
			(stroke
				(width 0.1)
				(type default)
			)
			(layer "F.Fab")
		)
		(fp_line
			(start 0.508 -0.3048)
			(end -0.508 -0.3048)
			(stroke
				(width 0.1)
				(type default)
			)
			(layer "F.Fab")
		)
		(fp_line
			(start 0.508 0.3048)
			(end 0.508 -0.3048)
			(stroke
				(width 0.1)
				(type default)
			)
			(layer "F.Fab")
		)
		(pad "1" smd rect
			(at -0.5334 0)
			(size 0.7112 0.6096)
			(layers "F.Cu" "F.Mask" "F.Paste")
			(net "XP3R3V_FPGA")
		)
		(pad "2" smd rect
			(at 0.5334 0)
			(size 0.7112 0.6096)
			(layers "F.Cu" "F.Mask" "F.Paste")
			(net "SG")
		)
		(zone
			(layer "F.Cu")
			(hatch none 0.5)
			(connect_pads
				(clearance 0)
			)
			(min_thickness 0.25)
			(keepout
				(tracks allowed)
				(vias not_allowed)
				(pads allowed)
				(copperpour not_allowed)
				(footprints allowed)
			)
			(placement
				(enabled no)
				(sheetname "")
			)
			(fill
				(thermal_gap 0.5)
				(thermal_bridge_width 0.5)
				(island_removal_mode 0)
			)
			(polygon
				(pts
					(xy 111.9632 -96.5708) (xy 111.8108 -96.5708) (xy 111.8108 -95.9612) (xy 111.9632 -95.9612)
				)
			)
		)
	)
	(footprint ""
		(layer "F.Cu")
		(at 132.334 -43.815)
		(property "Reference" "L12"
			(at -1.0795 -1.23063 0)
			(unlocked yes)
			(layer "F.SilkS")
			(effects
				(font
					(size 0.7874 0.5842)
					(thickness 0.1524)
				)
				(justify left)
			)
		)
		(property "Value" "VAL*"
			(at -0.9398 3.70967 0)
			(unlocked yes)
			(layer "F.Fab")
			(hide yes)
			(effects
				(font
					(size 0.7874 0.5842)
					(thickness 0.1524)
				)
				(justify left)
			)
		)
		(property "Tolerance" "TOL*"
			(at -0.9906 5.00507 0)
			(unlocked yes)
			(layer "Cmts.User")
			(hide yes)
			(effects
				(font
					(size 0.7874 0.5842)
					(thickness 0.1524)
				)
				(justify left)
			)
		)
		(property "User Part Number" "PARTNUM*"
			(at -2.54 2.46507 0)
			(unlocked yes)
			(layer "Cmts.User")
			(hide yes)
			(effects
				(font
					(size 0.7874 0.5842)
					(thickness 0.1524)
				)
				(justify left)
			)
		)
		(property "Device Type" "FERRITEBEAD-G191-10100-01,120OA"
			(at -0.9906 1.22047 0)
			(unlocked yes)
			(layer "F.Fab")
			(hide yes)
			(effects
				(font
					(size 0.7874 0.5842)
					(thickness 0.1524)
				)
				(justify left)
			)
		)
		(duplicate_pad_numbers_are_jumpers no)
		(fp_line
			(start -1.3208 -0.7112)
			(end 1.3208 -0.7112)
			(stroke
				(width 0.1)
				(type default)
			)
			(layer "F.SilkS")
		)
		(fp_line
			(start -1.3208 0.7112)
			(end -1.3208 -0.7112)
			(stroke
				(width 0.1)
				(type default)
			)
			(layer "F.SilkS")
		)
		(fp_line
			(start 1.3208 -0.7112)
			(end 1.3208 0.7112)
			(stroke
				(width 0.1)
				(type default)
			)
			(layer "F.SilkS")
		)
		(fp_line
			(start 1.3208 0.7112)
			(end -1.3208 0.7112)
			(stroke
				(width 0.1)
				(type default)
			)
			(layer "F.SilkS")
		)
		(fp_rect
			(start -1.3208 0.7112)
			(end 1.3208 -0.7112)
			(stroke
				(width 0)
				(type default)
			)
			(fill no)
			(layer "F.CrtYd")
		)
		(fp_line
			(start -0.8128 -0.4572)
			(end 0.8128 -0.4572)
			(stroke
				(width 0.1)
				(type default)
			)
			(layer "F.Fab")
		)
		(fp_line
			(start -0.8128 0.4572)
			(end -0.8128 -0.4572)
			(stroke
				(width 0.1)
				(type default)
			)
			(layer "F.Fab")
		)
		(fp_line
			(start 0.8128 -0.4572)
			(end 0.8128 0.4572)
			(stroke
				(width 0.1)
				(type default)
			)
			(layer "F.Fab")
		)
		(fp_line
			(start 0.8128 0.4572)
			(end -0.8128 0.4572)
			(stroke
				(width 0.1)
				(type default)
			)
			(layer "F.Fab")
		)
		(pad "1" smd rect
			(at -0.6858 0)
			(size 0.762 0.8636)
			(layers "F.Cu" "F.Mask" "F.Paste")
			(net "XP1R0V_FPGA_VCCINT")
		)
		(pad "2" smd rect
			(at 0.6858 0)
			(size 0.762 0.8636)
			(layers "F.Cu" "F.Mask" "F.Paste")
			(net "XP1R0V_FPGA")
		)
		(zone
			(layer "F.Cu")
			(hatch none 0.5)
			(connect_pads
				(clearance 0)
			)
			(min_thickness 0.25)
			(keepout
				(tracks allowed)
				(vias not_allowed)
				(pads allowed)
				(copperpour not_allowed)
				(footprints allowed)
			)
			(placement
				(enabled no)
				(sheetname "")
			)
			(fill
				(thermal_gap 0.5)
				(thermal_bridge_width 0.5)
				(island_removal_mode 0)
			)
			(polygon
				(pts
					(xy 132.1816 -43.3578) (xy 132.4864 -43.3578) (xy 132.4864 -44.2722) (xy 132.1816 -44.2722)
				)
			)
		)
		(zone
			(layer "F.Cu")
			(hatch none 0.5)
			(connect_pads
				(clearance 0)
			)
			(min_thickness 0.25)
			(keepout
				(tracks not_allowed)
				(vias allowed)
				(pads allowed)
				(copperpour not_allowed)
				(footprints allowed)
			)
			(placement
				(enabled no)
				(sheetname "")
			)
			(fill
				(thermal_gap 0.5)
				(thermal_bridge_width 0.5)
				(island_removal_mode 0)
			)
			(polygon
				(pts
					(xy 132.1816 -43.3578) (xy 132.4864 -43.3578) (xy 132.4864 -44.2722) (xy 132.1816 -44.2722)
				)
			)
		)
	)
	(footprint ""
		(layer "F.Cu")
		(at 57.404 -126.873)
		(property "Reference" "SP57"
			(at 0 0 0)
			(layer "F.SilkS")
			(hide yes)
			(effects
				(font
					(size 1.27 1.27)
				)
			)
		)
		(property "Value" ""
			(at 0 0 0)
			(layer "F.Fab")
			(effects
				(font
					(size 1.27 1.27)
				)
			)
		)
		(duplicate_pad_numbers_are_jumpers no)
	)
	(footprint ""
		(layer "F.Cu")
		(at 48.26 -126.238)
		(property "Reference" "SP26"
			(at 0 0 0)
			(layer "F.SilkS")
			(hide yes)
			(effects
				(font
					(size 1.27 1.27)
				)
			)
		)
		(property "Value" ""
			(at 0 0 0)
			(layer "F.Fab")
			(effects
				(font
					(size 1.27 1.27)
				)
			)
		)
		(duplicate_pad_numbers_are_jumpers no)
	)
)
